(kicad_pcb
	(version 20260206)
	(generator "pcbnew")
	(generator_version "10.0")
	(general
		(thickness 1.6)
		(legacy_teardrops no)
	)
	(paper "A4")
	(title_block
		(title "fcb — Lightning_FCB_BRD.brd")
		(comment 1 "Lightning (Wiwynn / Facebook NVMe JBOF) / footprints 196-199 of 495")
	)
	(layers
		(0 "F.Cu" signal "TOP")
		(4 "In1.Cu" signal "L2GND")
		(6 "In2.Cu" signal "L3VCC")
		(2 "B.Cu" signal "BOTTOM")
		(9 "F.Adhes" user "F.Adhesive")
		(11 "B.Adhes" user "B.Adhesive")
		(13 "F.Paste" user "Package Geometry/Pastemask Top")
		(15 "B.Paste" user "Package Geometry/Pastemask Bottom")
		(5 "F.SilkS" user "Ref Des/Silkscreen Top")
		(7 "B.SilkS" user "Ref Des/Silkscreen Bottom")
		(1 "F.Mask" user "Board Geometry/Soldermask Top")
		(3 "B.Mask" user "Board Geometry/Soldermask Bottom")
		(17 "Dwgs.User" user "User.Drawings")
		(19 "Cmts.User" user "User.Comments")
		(21 "Eco1.User" user "User.Eco1")
		(23 "Eco2.User" user "User.Eco2")
		(25 "Edge.Cuts" user "Board Geometry/Outline")
		(27 "Margin" user)
		(31 "F.CrtYd" user "Package Geometry/Place Bound Top")
		(29 "B.CrtYd" user "Package Geometry/Place Bound Bottom")
		(35 "F.Fab" user "Ref Des/Assembly Top")
		(33 "B.Fab" user "Ref Des/Assembly Bottom")
	)
	(footprint ""
		(layer "F.Cu")
		(at 6.999986 -459.999842)
		(property "Reference" "H5"
			(at 0 0 0)
			(layer "F.SilkS")
			(hide yes)
			(effects
				(font
					(size 1.27 1.27)
				)
			)
		)
		(property "Value" "HOLE315R138"
			(at 0 -7.0612 0)
			(unlocked yes)
			(layer "F.Fab")
			(hide yes)
			(effects
				(font
					(size 1.016 1.016)
					(thickness 0.1524)
				)
			)
		)
		(property "Device Type" "HOLE315R138"
			(at 0 -8.5852 0)
			(unlocked yes)
			(layer "F.Fab")
			(hide yes)
			(effects
				(font
					(size 1.016 1.016)
					(thickness 0.1524)
				)
			)
		)
		(duplicate_pad_numbers_are_jumpers no)
		(fp_poly
			(pts
				(xy 0 4.3053) (xy -0.13462 4.30276) (xy -0.27051 4.29641) (xy -0.40513 4.28625) (xy -0.53975 4.27101)
				(xy -0.6731 4.25196) (xy -0.80645 4.2291) (xy -0.9398 4.20116) (xy -1.07061 4.17068) (xy -1.20142 4.13385)
				(xy -1.33096 4.09448) (xy -1.45796 4.0513) (xy -1.58496 4.00304) (xy -1.70942 3.95097) (xy -1.83261 3.89509)
				(xy -1.95453 3.83667) (xy -2.07391 3.77317) (xy -2.19202 3.70586) (xy -2.30632 3.63474) (xy -2.41935 3.56108)
				(xy -2.53111 3.48361) (xy -2.63906 3.40233) (xy -2.74447 3.31724) (xy -2.84734 3.22961) (xy -2.94767 3.13817)
				(xy -3.04419 3.04419) (xy -3.13817 2.94767) (xy -3.22961 2.84734) (xy -3.31724 2.74447) (xy -3.40233 2.63906)
				(xy -3.48361 2.53111) (xy -3.56108 2.41935) (xy -3.63474 2.30632) (xy -3.70586 2.19202) (xy -3.77317 2.07391)
				(xy -3.83667 1.95453) (xy -3.89509 1.83261) (xy -3.95097 1.70942) (xy -4.00304 1.58496) (xy -4.0513 1.45796)
				(xy -4.09448 1.33096) (xy -4.13385 1.20142) (xy -4.17068 1.07061) (xy -4.20116 0.9398) (xy -4.2291 0.80645)
				(xy -4.25196 0.6731) (xy -4.27101 0.53975) (xy -4.28625 0.40513) (xy -4.29641 0.27051) (xy -4.30276 0.13462)
				(xy -4.3053 0) (xy -4.30276 -0.13462) (xy -4.29641 -0.27051) (xy -4.28625 -0.40513) (xy -4.27101 -0.53975)
				(xy -4.25196 -0.6731) (xy -4.2291 -0.80645) (xy -4.20116 -0.9398) (xy -4.17068 -1.07061) (xy -4.13385 -1.20142)
				(xy -4.09448 -1.33096) (xy -4.0513 -1.45796) (xy -4.00304 -1.58496) (xy -3.95097 -1.70942) (xy -3.89509 -1.83261)
				(xy -3.83667 -1.95453) (xy -3.77317 -2.07391) (xy -3.70586 -2.19202) (xy -3.63474 -2.30632) (xy -3.56108 -2.41935)
				(xy -3.48361 -2.53111) (xy -3.40233 -2.63906) (xy -3.31724 -2.74447) (xy -3.22961 -2.84734) (xy -3.13817 -2.94767)
				(xy -3.04419 -3.04419) (xy -2.94767 -3.13817) (xy -2.84734 -3.22961) (xy -2.74447 -3.31724) (xy -2.63906 -3.40233)
				(xy -2.53111 -3.48361) (xy -2.41935 -3.56108) (xy -2.30632 -3.63474) (xy -2.19202 -3.70586) (xy -2.07391 -3.77317)
				(xy -1.95453 -3.83667) (xy -1.83261 -3.89509) (xy -1.70942 -3.95097) (xy -1.58496 -4.00304) (xy -1.45796 -4.0513)
				(xy -1.33096 -4.09448) (xy -1.20142 -4.13385) (xy -1.07061 -4.17068) (xy -0.9398 -4.20116) (xy -0.80645 -4.2291)
				(xy -0.6731 -4.25196) (xy -0.53975 -4.27101) (xy -0.40513 -4.28625) (xy -0.27051 -4.29641) (xy -0.13462 -4.30276)
				(xy 0 -4.3053) (xy 0.13462 -4.30276) (xy 0.27051 -4.29641) (xy 0.40513 -4.28625) (xy 0.53975 -4.27101)
				(xy 0.6731 -4.25196) (xy 0.80645 -4.2291) (xy 0.9398 -4.20116) (xy 1.07061 -4.17068) (xy 1.20142 -4.13385)
				(xy 1.33096 -4.09448) (xy 1.45796 -4.0513) (xy 1.58496 -4.00304) (xy 1.70942 -3.95097) (xy 1.83261 -3.89509)
				(xy 1.95453 -3.83667) (xy 2.07391 -3.77317) (xy 2.19202 -3.70586) (xy 2.30632 -3.63474) (xy 2.41935 -3.56108)
				(xy 2.53111 -3.48361) (xy 2.63906 -3.40233) (xy 2.74447 -3.31724) (xy 2.84734 -3.22961) (xy 2.94767 -3.13817)
				(xy 3.04419 -3.04419) (xy 3.13817 -2.94767) (xy 3.22961 -2.84734) (xy 3.31724 -2.74447) (xy 3.40233 -2.63906)
				(xy 3.48361 -2.53111) (xy 3.56108 -2.41935) (xy 3.63474 -2.30632) (xy 3.70586 -2.19202) (xy 3.77317 -2.07391)
				(xy 3.83667 -1.95453) (xy 3.89509 -1.83261) (xy 3.95097 -1.70942) (xy 4.00304 -1.58496) (xy 4.0513 -1.45796)
				(xy 4.09448 -1.33096) (xy 4.13385 -1.20142) (xy 4.17068 -1.07061) (xy 4.20116 -0.9398) (xy 4.2291 -0.80645)
				(xy 4.25196 -0.6731) (xy 4.27101 -0.53975) (xy 4.28625 -0.40513) (xy 4.29641 -0.27051) (xy 4.30276 -0.13462)
				(xy 4.3053 0) (xy 4.30276 0.13462) (xy 4.29641 0.27051) (xy 4.28625 0.40513) (xy 4.27101 0.53975)
				(xy 4.25196 0.6731) (xy 4.2291 0.80645) (xy 4.20116 0.9398) (xy 4.17068 1.07061) (xy 4.13385 1.20142)
				(xy 4.09448 1.33096) (xy 4.0513 1.45796) (xy 4.00304 1.58496) (xy 3.95097 1.70942) (xy 3.89509 1.83261)
				(xy 3.83667 1.95453) (xy 3.77317 2.07391) (xy 3.70586 2.19202) (xy 3.63474 2.30632) (xy 3.56108 2.41935)
				(xy 3.48361 2.53111) (xy 3.40233 2.63906) (xy 3.31724 2.74447) (xy 3.22961 2.84734) (xy 3.13817 2.94767)
				(xy 3.04419 3.04419) (xy 2.94767 3.13817) (xy 2.84734 3.22961) (xy 2.74447 3.31724) (xy 2.63906 3.40233)
				(xy 2.53111 3.48361) (xy 2.41935 3.56108) (xy 2.30632 3.63474) (xy 2.19202 3.70586) (xy 2.07391 3.77317)
				(xy 1.95453 3.83667) (xy 1.83261 3.89509) (xy 1.70942 3.95097) (xy 1.58496 4.00304) (xy 1.45796 4.0513)
				(xy 1.33096 4.09448) (xy 1.20142 4.13385) (xy 1.07061 4.17068) (xy 0.9398 4.20116) (xy 0.80645 4.2291)
				(xy 0.6731 4.25196) (xy 0.53975 4.27101) (xy 0.40513 4.28625) (xy 0.27051 4.29641) (xy 0.13462 4.30276)
			)
			(stroke
				(width 0)
				(type default)
			)
			(fill no)
			(layer "F.CrtYd")
		)
		(fp_poly
			(pts
				(xy 0 4.3053) (xy -0.13462 4.30276) (xy -0.27051 4.29641) (xy -0.40513 4.28625) (xy -0.53975 4.27101)
				(xy -0.6731 4.25196) (xy -0.80645 4.2291) (xy -0.9398 4.20116) (xy -1.07061 4.17068) (xy -1.20142 4.13385)
				(xy -1.33096 4.09448) (xy -1.45796 4.0513) (xy -1.58496 4.00304) (xy -1.70942 3.95097) (xy -1.83261 3.89509)
				(xy -1.95453 3.83667) (xy -2.07391 3.77317) (xy -2.19202 3.70586) (xy -2.30632 3.63474) (xy -2.41935 3.56108)
				(xy -2.53111 3.48361) (xy -2.63906 3.40233) (xy -2.74447 3.31724) (xy -2.84734 3.22961) (xy -2.94767 3.13817)
				(xy -3.04419 3.04419) (xy -3.13817 2.94767) (xy -3.22961 2.84734) (xy -3.31724 2.74447) (xy -3.40233 2.63906)
				(xy -3.48361 2.53111) (xy -3.56108 2.41935) (xy -3.63474 2.30632) (xy -3.70586 2.19202) (xy -3.77317 2.07391)
				(xy -3.83667 1.95453) (xy -3.89509 1.83261) (xy -3.95097 1.70942) (xy -4.00304 1.58496) (xy -4.0513 1.45796)
				(xy -4.09448 1.33096) (xy -4.13385 1.20142) (xy -4.17068 1.07061) (xy -4.20116 0.9398) (xy -4.2291 0.80645)
				(xy -4.25196 0.6731) (xy -4.27101 0.53975) (xy -4.28625 0.40513) (xy -4.29641 0.27051) (xy -4.30276 0.13462)
				(xy -4.3053 0) (xy -4.30276 -0.13462) (xy -4.29641 -0.27051) (xy -4.28625 -0.40513) (xy -4.27101 -0.53975)
				(xy -4.25196 -0.6731) (xy -4.2291 -0.80645) (xy -4.20116 -0.9398) (xy -4.17068 -1.07061) (xy -4.13385 -1.20142)
				(xy -4.09448 -1.33096) (xy -4.0513 -1.45796) (xy -4.00304 -1.58496) (xy -3.95097 -1.70942) (xy -3.89509 -1.83261)
				(xy -3.83667 -1.95453) (xy -3.77317 -2.07391) (xy -3.70586 -2.19202) (xy -3.63474 -2.30632) (xy -3.56108 -2.41935)
				(xy -3.48361 -2.53111) (xy -3.40233 -2.63906) (xy -3.31724 -2.74447) (xy -3.22961 -2.84734) (xy -3.13817 -2.94767)
				(xy -3.04419 -3.04419) (xy -2.94767 -3.13817) (xy -2.84734 -3.22961) (xy -2.74447 -3.31724) (xy -2.63906 -3.40233)
				(xy -2.53111 -3.48361) (xy -2.41935 -3.56108) (xy -2.30632 -3.63474) (xy -2.19202 -3.70586) (xy -2.07391 -3.77317)
				(xy -1.95453 -3.83667) (xy -1.83261 -3.89509) (xy -1.70942 -3.95097) (xy -1.58496 -4.00304) (xy -1.45796 -4.0513)
				(xy -1.33096 -4.09448) (xy -1.20142 -4.13385) (xy -1.07061 -4.17068) (xy -0.9398 -4.20116) (xy -0.80645 -4.2291)
				(xy -0.6731 -4.25196) (xy -0.53975 -4.27101) (xy -0.40513 -4.28625) (xy -0.27051 -4.29641) (xy -0.13462 -4.30276)
				(xy 0 -4.3053) (xy 0.13462 -4.30276) (xy 0.27051 -4.29641) (xy 0.40513 -4.28625) (xy 0.53975 -4.27101)
				(xy 0.6731 -4.25196) (xy 0.80645 -4.2291) (xy 0.9398 -4.20116) (xy 1.07061 -4.17068) (xy 1.20142 -4.13385)
				(xy 1.33096 -4.09448) (xy 1.45796 -4.0513) (xy 1.58496 -4.00304) (xy 1.70942 -3.95097) (xy 1.83261 -3.89509)
				(xy 1.95453 -3.83667) (xy 2.07391 -3.77317) (xy 2.19202 -3.70586) (xy 2.30632 -3.63474) (xy 2.41935 -3.56108)
				(xy 2.53111 -3.48361) (xy 2.63906 -3.40233) (xy 2.74447 -3.31724) (xy 2.84734 -3.22961) (xy 2.94767 -3.13817)
				(xy 3.04419 -3.04419) (xy 3.13817 -2.94767) (xy 3.22961 -2.84734) (xy 3.31724 -2.74447) (xy 3.40233 -2.63906)
				(xy 3.48361 -2.53111) (xy 3.56108 -2.41935) (xy 3.63474 -2.30632) (xy 3.70586 -2.19202) (xy 3.77317 -2.07391)
				(xy 3.83667 -1.95453) (xy 3.89509 -1.83261) (xy 3.95097 -1.70942) (xy 4.00304 -1.58496) (xy 4.0513 -1.45796)
				(xy 4.09448 -1.33096) (xy 4.13385 -1.20142) (xy 4.17068 -1.07061) (xy 4.20116 -0.9398) (xy 4.2291 -0.80645)
				(xy 4.25196 -0.6731) (xy 4.27101 -0.53975) (xy 4.28625 -0.40513) (xy 4.29641 -0.27051) (xy 4.30276 -0.13462)
				(xy 4.3053 0) (xy 4.30276 0.13462) (xy 4.29641 0.27051) (xy 4.28625 0.40513) (xy 4.27101 0.53975)
				(xy 4.25196 0.6731) (xy 4.2291 0.80645) (xy 4.20116 0.9398) (xy 4.17068 1.07061) (xy 4.13385 1.20142)
				(xy 4.09448 1.33096) (xy 4.0513 1.45796) (xy 4.00304 1.58496) (xy 3.95097 1.70942) (xy 3.89509 1.83261)
				(xy 3.83667 1.95453) (xy 3.77317 2.07391) (xy 3.70586 2.19202) (xy 3.63474 2.30632) (xy 3.56108 2.41935)
				(xy 3.48361 2.53111) (xy 3.40233 2.63906) (xy 3.31724 2.74447) (xy 3.22961 2.84734) (xy 3.13817 2.94767)
				(xy 3.04419 3.04419) (xy 2.94767 3.13817) (xy 2.84734 3.22961) (xy 2.74447 3.31724) (xy 2.63906 3.40233)
				(xy 2.53111 3.48361) (xy 2.41935 3.56108) (xy 2.30632 3.63474) (xy 2.19202 3.70586) (xy 2.07391 3.77317)
				(xy 1.95453 3.83667) (xy 1.83261 3.89509) (xy 1.70942 3.95097) (xy 1.58496 4.00304) (xy 1.45796 4.0513)
				(xy 1.33096 4.09448) (xy 1.20142 4.13385) (xy 1.07061 4.17068) (xy 0.9398 4.20116) (xy 0.80645 4.2291)
				(xy 0.6731 4.25196) (xy 0.53975 4.27101) (xy 0.40513 4.28625) (xy 0.27051 4.29641) (xy 0.13462 4.30276)
			)
			(stroke
				(width 0)
				(type default)
			)
			(fill no)
			(layer "F.Fab")
		)
		(pad "1" thru_hole circle
			(at 0 0)
			(size 8.001 8.001)
			(drill 3.5052)
			(layers "*.Cu" "*.Mask")
			(remove_unused_layers no)
			(net "GND")
			(clearance -1.7399)
			(thermal_gap 0.3048)
			(padstack
				(mode front_inner_back)
				(layer "Inner"
					(shape circle)
					(size 3.9116 3.9116)
					(clearance 0.3048)
				)
				(layer "B.Cu"
					(shape circle)
					(size 8.001 8.001)
					(clearance -1.7399)
				)
			)
		)
	)
	(footprint ""
		(layer "F.Cu")
		(at 37.211 -378.333 180)
		(property "Reference" "PR27"
			(at 0 0 180)
			(layer "F.SilkS")
			(hide yes)
			(effects
				(font
					(size 1.27 1.27)
				)
			)
		)
		(property "Value" "10R2F-L-GP"
			(at 0.064008 -3.993896 180)
			(unlocked yes)
			(layer "F.Fab")
			(hide yes)
			(effects
				(font
					(size 1.016 1.016)
					(thickness 0.1524)
				)
			)
		)
		(property "Device Type" "R402H14"
			(at 0.064008 -5.517896 180)
			(unlocked yes)
			(layer "F.Fab")
			(hide yes)
			(effects
				(font
					(size 1.016 1.016)
					(thickness 0.1524)
				)
			)
		)
		(duplicate_pad_numbers_are_jumpers no)
		(fp_line
			(start 0.508 -0.9398)
			(end -0.508 -0.9398)
			(stroke
				(width 0.1524)
				(type default)
			)
			(layer "F.SilkS")
		)
		(fp_line
			(start -0.508 -0.9398)
			(end -0.508 0.9398)
			(stroke
				(width 0.1524)
				(type default)
			)
			(layer "F.SilkS")
		)
		(fp_rect
			(start -0.508 0.9398)
			(end 0.508 -0.9398)
			(stroke
				(width 0)
				(type default)
			)
			(fill no)
			(layer "F.CrtYd")
		)
		(fp_rect
			(start -0.508 0.9398)
			(end 0.508 -0.9398)
			(stroke
				(width 0)
				(type default)
			)
			(fill no)
			(layer "F.Fab")
		)
		(pad "1" smd custom
			(at 0 -0.4445 180)
			(size 0.1397 0.1397)
			(layers "F.Cu" "F.Mask" "F.Paste")
			(net "ADM1276_GATE")
			(options
				(clearance outline)
				(anchor circle)
			)
			(primitives
				(gr_poly
					(pts
						(arc
							(start -0.1778 -0.2794)
							(mid -0.249642 -0.249642)
							(end -0.2794 -0.1778)
						)
						(arc
							(start -0.2794 0.1778)
							(mid -0.249642 0.249642)
							(end -0.1778 0.2794)
						)
						(arc
							(start 0.1778 0.2794)
							(mid 0.249642 0.249642)
							(end 0.2794 0.1778)
						)
						(arc
							(start 0.2794 -0.1778)
							(mid 0.249642 -0.249642)
							(end 0.1778 -0.2794)
						)
					)
					(width 0)
					(fill yes)
				)
			)
		)
		(pad "2" smd custom
			(at 0 0.4445 180)
			(size 0.1397 0.1397)
			(layers "F.Cu" "F.Mask" "F.Paste")
			(net "ADM1276_GATE_DRV2")
			(options
				(clearance outline)
				(anchor circle)
			)
			(primitives
				(gr_poly
					(pts
						(arc
							(start -0.1778 -0.2794)
							(mid -0.249642 -0.249642)
							(end -0.2794 -0.1778)
						)
						(arc
							(start -0.2794 0.1778)
							(mid -0.249642 0.249642)
							(end -0.1778 0.2794)
						)
						(arc
							(start 0.1778 0.2794)
							(mid 0.249642 0.249642)
							(end 0.2794 0.1778)
						)
						(arc
							(start 0.2794 -0.1778)
							(mid 0.249642 -0.249642)
							(end 0.1778 -0.2794)
						)
					)
					(width 0)
					(fill yes)
				)
			)
		)
	)
	(footprint ""
		(layer "F.Cu")
		(at 22.733 -372.237 180)
		(property "Reference" "PC9"
			(at 0 0 180)
			(layer "F.SilkS")
			(hide yes)
			(effects
				(font
					(size 1.27 1.27)
				)
			)
		)
		(property "Value" "SC1U25V5KX-1GP"
			(at -0.0762 -6.1214 180)
			(unlocked yes)
			(layer "F.Fab")
			(hide yes)
			(effects
				(font
					(size 1.016 1.016)
					(thickness 0.1524)
				)
			)
		)
		(property "Device Type" "C805H58"
			(at -0.0762 -8.1534 180)
			(unlocked yes)
			(layer "F.Fab")
			(hide yes)
			(effects
				(font
					(size 1.016 1.016)
					(thickness 0.1524)
				)
			)
		)
		(duplicate_pad_numbers_are_jumpers no)
		(fp_line
			(start 0.635 0)
			(end -0.635 0)
			(stroke
				(width 0.508)
				(type default)
			)
			(layer "F.SilkS")
		)
		(fp_rect
			(start -0.9652 1.778)
			(end 0.9652 -1.778)
			(stroke
				(width 0)
				(type default)
			)
			(fill no)
			(layer "F.CrtYd")
		)
		(fp_poly
			(pts
				(xy -0.9652 -1.778) (xy 0.9652 -1.778) (xy 0.9652 1.778) (xy -0.9652 1.778)
			)
			(stroke
				(width 0)
				(type default)
			)
			(fill no)
			(layer "F.Fab")
		)
		(pad "1" smd rect
			(at 0 -0.9652 180)
			(size 1.397 1.143)
			(layers "F.Cu" "F.Mask" "F.Paste")
			(net "ADM1276_OV")
		)
		(pad "2" smd rect
			(at 0 0.9652 180)
			(size 1.397 1.143)
			(layers "F.Cu" "F.Mask" "F.Paste")
			(net "GND")
		)
	)
	(footprint ""
		(layer "F.Cu")
		(at 21.8948 -197.2818 90)
		(property "Reference" "R180"
			(at 0 0 90)
			(layer "F.SilkS")
			(hide yes)
			(effects
				(font
					(size 1.27 1.27)
				)
			)
		)
		(property "Value" "0R1206-PAD-1-GP"
			(at 0 -5.0292 90)
			(unlocked yes)
			(layer "F.Fab")
			(hide yes)
			(effects
				(font
					(size 1.016 1.016)
					(thickness 0.1524)
				)
			)
		)
		(property "Device Type" "0R1206-PAD-1"
			(at 0 -6.5532 90)
			(unlocked yes)
			(layer "F.Fab")
			(hide yes)
			(effects
				(font
					(size 1.016 1.016)
					(thickness 0.1524)
				)
			)
		)
		(duplicate_pad_numbers_are_jumpers no)
		(fp_line
			(start 1.016 -2.2352)
			(end -1.016 -2.2352)
			(stroke
				(width 0.1524)
				(type default)
			)
			(layer "F.SilkS")
		)
		(fp_line
			(start -1.016 -2.2352)
			(end -1.016 2.2352)
			(stroke
				(width 0.1524)
				(type default)
			)
			(layer "F.SilkS")
		)
		(fp_line
			(start 1.016 2.2352)
			(end 1.016 -2.2352)
			(stroke
				(width 0.1524)
				(type default)
			)
			(layer "F.SilkS")
		)
		(fp_line
			(start -1.016 2.2352)
			(end 1.016 2.2352)
			(stroke
				(width 0.1524)
				(type default)
			)
			(layer "F.SilkS")
		)
		(fp_rect
			(start -1.0922 2.3114)
			(end 1.0922 -2.3114)
			(stroke
				(width 0)
				(type default)
			)
			(fill no)
			(layer "F.CrtYd")
		)
		(fp_poly
			(pts
				(xy -1.0922 -2.3114) (xy 1.0922 -2.3114) (xy 1.0922 2.3114) (xy -1.0922 2.3114)
			)
			(stroke
				(width 0)
				(type default)
			)
			(fill no)
			(layer "F.Fab")
		)
		(pad "1" smd rect
			(at 0 -1.397 90)
			(size 1.651 2.0574)
			(drill
				(offset 0 0.3937)
			)
			(layers "F.Cu" "F.Mask" "F.Paste")
			(net "P12V_FAN4")
		)
		(pad "2" smd rect
			(at 0 1.397 90)
			(size 1.651 2.0574)
			(drill
				(offset 0 -0.3937)
			)
			(layers "F.Cu" "F.Mask" "F.Paste")
			(net "P12V")
		)
	)
)
